(kicad_pcb
	(version 20241229)
	(generator "pcbnew")
	(generator_version "9.0")
	(general
		(thickness 1.61)
		(legacy_teardrops no)
	)
	(paper "A3")
	(title_block
		(title "RDIMM DDR5 Tester")
		(date "2026-05-21")
		(rev "2.2.0")
		(company "Antmicro")
		(comment 9 "footprint 119 of 796 (U34), pads 537-605 of 676")
	)
	(layers
		(0 "F.Cu" signal)
		(4 "In1.Cu" power)
		(6 "In2.Cu" mixed)
		(8 "In3.Cu" power)
		(10 "In4.Cu" mixed)
		(12 "In5.Cu" power)
		(14 "In6.Cu" mixed)
		(16 "In7.Cu" power)
		(18 "In8.Cu" power)
		(20 "In9.Cu" mixed)
		(22 "In10.Cu" power)
		(2 "B.Cu" signal)
		(9 "F.Adhes" user "F.Adhesive")
		(11 "B.Adhes" user "B.Adhesive")
		(13 "F.Paste" user)
		(15 "B.Paste" user)
		(5 "F.SilkS" user "F.Silkscreen")
		(7 "B.SilkS" user "B.Silkscreen")
		(1 "F.Mask" user)
		(3 "B.Mask" user)
		(17 "Dwgs.User" user "User.Drawings")
		(19 "Cmts.User" user "User.Comments")
		(21 "Eco1.User" user "User.Eco1")
		(23 "Eco2.User" user "User.Eco2")
		(25 "Edge.Cuts" user)
		(27 "Margin" user)
		(31 "F.CrtYd" user "F.Courtyard")
		(29 "B.CrtYd" user "B.Courtyard")
		(35 "F.Fab" user)
		(33 "B.Fab" user)
	)
	(footprint "antmicro-footprints:BGA-676_27x27mm_Layout26x26_P1x1mm_FFVB676"
		(layer "F.Cu")
		(at 188.5 152.5 90)
		(property "Reference" "U34"
			(at -14.72 12.46 180)
			(layer "F.SilkS")
			(effects
				(font
					(size 0.7 0.7)
					(thickness 0.15)
				)
				(justify left bottom)
			)
		)
		(property "Value" "XCAU25P-2FFVB676I"
			(at 0 15.5 90)
			(layer "F.Fab")
			(effects
				(font
					(size 0.7 0.7)
					(thickness 0.15)
				)
				(justify left bottom)
			)
		)
		(property "Datasheet" "https://docs.xilinx.com/viewer/book-attachment/2PXOpPtpaABIt0fkzeBLnw/hvbsEUaOT0OxFhln7VEVyA"
			(at 0 0 90)
			(layer "F.Fab")
			(hide yes)
			(effects
				(font
					(size 1.27 1.27)
					(thickness 0.15)
				)
			)
		)
		(property "MPN" "XCAU25P-2FFVB676I"
			(at 0 0 90)
			(unlocked yes)
			(layer "F.Fab")
			(hide yes)
			(effects
				(font
					(size 1 1)
					(thickness 0.15)
				)
			)
		)
		(property "Manufacturer" "AMD-Xilinx"
			(at 0 0 90)
			(unlocked yes)
			(layer "F.Fab")
			(hide yes)
			(effects
				(font
					(size 1 1)
					(thickness 0.15)
				)
			)
		)
		(property "Author" "Antmicro"
			(at 0 0 90)
			(unlocked yes)
			(layer "F.Fab")
			(hide yes)
			(effects
				(font
					(size 1 1)
					(thickness 0.15)
				)
			)
		)
		(property "License" "Apache-2.0"
			(at 0 0 90)
			(unlocked yes)
			(layer "F.Fab")
			(hide yes)
			(effects
				(font
					(size 1 1)
					(thickness 0.15)
				)
			)
		)
		(sheetname "/FPGA Config/")
		(sheetfile "fpga-config.kicad_sch")
		(attr smd)
		(pad "R17" smd circle
			(at 3.5 1.5 90)
			(size 0.5 0.5)
			(layers "F.Cu" "F.Mask" "F.Paste")
			(net 1 "GND")
			(pinfunction "GND")
			(pintype "passive")
			(solder_mask_margin 0.075)
		)
		(pad "R18" smd circle
			(at 4.5 1.5 90)
			(size 0.5 0.5)
			(layers "F.Cu" "F.Mask" "F.Paste")
			(net 797 "+1V8")
			(pinfunction "VCCAUX_IO")
			(pintype "passive")
			(solder_mask_margin 0.075)
		)
		(pad "R19" smd circle
			(at 5.5 1.5 90)
			(size 0.5 0.5)
			(layers "F.Cu" "F.Mask" "F.Paste")
			(net 1 "GND")
			(pinfunction "GND")
			(pintype "passive")
			(solder_mask_margin 0.075)
		)
		(pad "R20" smd circle
			(at 6.5 1.5 90)
			(size 0.5 0.5)
			(layers "F.Cu" "F.Mask" "F.Paste")
			(net 204 "/DDR5 RDIMM/B.CB6")
			(pinfunction "IO_L21P_T3L_N4_AD8P_D06_65")
			(pintype "bidirectional")
			(die_length 14.707)
			(solder_mask_margin 0.075)
		)
		(pad "R21" smd circle
			(at 7.5 1.5 90)
			(size 0.5 0.5)
			(layers "F.Cu" "F.Mask" "F.Paste")
			(net 100 "/DDR5 RDIMM/B.CB5")
			(pinfunction "IO_L21N_T3L_N5_AD8N_D07_65")
			(pintype "bidirectional")
			(die_length 13.954)
			(solder_mask_margin 0.075)
		)
		(pad "R22" smd circle
			(at 8.5 1.5 90)
			(size 0.5 0.5)
			(layers "F.Cu" "F.Mask" "F.Paste")
			(net 126 "/DDR5 RDIMM/B.DQS9_P")
			(pinfunction "IO_L19P_T3L_N0_DBC_AD9P_D10_65")
			(pintype "bidirectional")
			(die_length 10.97)
			(solder_mask_margin 0.075)
		)
		(pad "R23" smd circle
			(at 9.5 1.5 90)
			(size 0.5 0.5)
			(layers "F.Cu" "F.Mask" "F.Paste")
			(net 127 "/DDR5 RDIMM/B.DQS9_N")
			(pinfunction "IO_L19N_T3L_N1_DBC_AD9N_D11_65")
			(pintype "bidirectional")
			(die_length 10.922)
			(solder_mask_margin 0.075)
		)
		(pad "R24" smd circle
			(at 10.5 1.5 90)
			(size 0.5 0.5)
			(layers "F.Cu" "F.Mask" "F.Paste")
			(net 1 "GND")
			(pinfunction "GND")
			(pintype "passive")
			(solder_mask_margin 0.075)
		)
		(pad "R25" smd circle
			(at 11.5 1.5 90)
			(size 0.5 0.5)
			(layers "F.Cu" "F.Mask" "F.Paste")
			(net 80 "/DDR5 RDIMM/B.CA1")
			(pinfunction "IO_L18P_T2U_N10_AD2P_D12_65")
			(pintype "bidirectional")
			(die_length 11.555)
			(solder_mask_margin 0.075)
		)
		(pad "R26" smd circle
			(at 12.5 1.5 90)
			(size 0.5 0.5)
			(layers "F.Cu" "F.Mask" "F.Paste")
			(net 202 "/DDR5 RDIMM/B.PAR")
			(pinfunction "IO_L18N_T2U_N11_AD2N_D13_65")
			(pintype "bidirectional")
			(die_length 11.586)
			(solder_mask_margin 0.075)
		)
		(pad "T1" smd circle
			(at -12.5 2.5 90)
			(size 0.5 0.5)
			(layers "F.Cu" "F.Mask" "F.Paste")
			(net 335 "/FPGA MGT Interface/PCIE.RXD1_N")
			(pinfunction "MGTYRXN2_225")
			(pintype "input")
			(die_length 9.796)
			(solder_mask_margin 0.075)
		)
		(pad "T2" smd circle
			(at -11.5 2.5 90)
			(size 0.5 0.5)
			(layers "F.Cu" "F.Mask" "F.Paste")
			(net 334 "/FPGA MGT Interface/PCIE.RXD1_P")
			(pinfunction "MGTYRXP2_225")
			(pintype "input")
			(die_length 9.777)
			(solder_mask_margin 0.075)
		)
		(pad "T3" smd circle
			(at -10.5 2.5 90)
			(size 0.5 0.5)
			(layers "F.Cu" "F.Mask" "F.Paste")
			(net 1 "GND")
			(pinfunction "GND")
			(pintype "passive")
			(solder_mask_margin 0.075)
		)
		(pad "T4" smd circle
			(at -9.5 2.5 90)
			(size 0.5 0.5)
			(layers "F.Cu" "F.Mask" "F.Paste")
			(net 1 "GND")
			(pinfunction "GND")
			(pintype "passive")
			(solder_mask_margin 0.075)
		)
		(pad "T5" smd circle
			(at -8.5 2.5 90)
			(size 0.5 0.5)
			(layers "F.Cu" "F.Mask" "F.Paste")
			(net 172 "+1V2_MGTAVTT")
			(pinfunction "MGTAVTT_R")
			(pintype "passive")
			(solder_mask_margin 0.075)
		)
		(pad "T6" smd circle
			(at -7.5 2.5 90)
			(size 0.5 0.5)
			(layers "F.Cu" "F.Mask" "F.Paste")
			(net 560 "unconnected-(U34J-MGTREFCLK1N_225-PadT6)")
			(pinfunction "MGTREFCLK1N_225")
			(pintype "input+no_connect")
			(die_length 6.993)
			(solder_mask_margin 0.075)
		)
		(pad "T7" smd circle
			(at -6.5 2.5 90)
			(size 0.5 0.5)
			(layers "F.Cu" "F.Mask" "F.Paste")
			(net 561 "unconnected-(U34J-MGTREFCLK1P_225-PadT7)")
			(pinfunction "MGTREFCLK1P_225")
			(pintype "input+no_connect")
			(die_length 6.98)
			(solder_mask_margin 0.075)
		)
		(pad "T8" smd circle
			(at -5.5 2.5 90)
			(size 0.5 0.5)
			(layers "F.Cu" "F.Mask" "F.Paste")
			(net 1 "GND")
			(pinfunction "GND")
			(pintype "passive")
			(solder_mask_margin 0.075)
		)
		(pad "T9" smd circle
			(at -4.5 2.5 90)
			(size 0.5 0.5)
			(layers "F.Cu" "F.Mask" "F.Paste")
			(net 553 "+0V85")
			(pinfunction "VCCBRAM")
			(pintype "passive")
			(solder_mask_margin 0.075)
		)
		(pad "T10" smd circle
			(at -3.5 2.5 90)
			(size 0.5 0.5)
			(layers "F.Cu" "F.Mask" "F.Paste")
			(net 1 "GND")
			(pinfunction "GND")
			(pintype "passive")
			(solder_mask_margin 0.075)
		)
		(pad "T11" smd circle
			(at -2.5 2.5 90)
			(size 0.5 0.5)
			(layers "F.Cu" "F.Mask" "F.Paste")
			(net 553 "+0V85")
			(pinfunction "VCCINT")
			(pintype "passive")
			(solder_mask_margin 0.075)
		)
		(pad "T12" smd circle
			(at -1.5 2.5 90)
			(size 0.5 0.5)
			(layers "F.Cu" "F.Mask" "F.Paste")
			(net 1 "GND")
			(pinfunction "GND")
			(pintype "passive")
			(solder_mask_margin 0.075)
		)
		(pad "T13" smd circle
			(at -0.5 2.5 90)
			(size 0.5 0.5)
			(layers "F.Cu" "F.Mask" "F.Paste")
			(net 667 "/FPGA Config/DX_N")
			(pinfunction "DXN")
			(pintype "passive")
			(die_length 11.82)
			(solder_mask_margin 0.075)
		)
		(pad "T14" smd circle
			(at 0.5 2.5 90)
			(size 0.5 0.5)
			(layers "F.Cu" "F.Mask" "F.Paste")
			(net 668 "/FPGA Config/DX_P")
			(pinfunction "DXP")
			(pintype "passive")
			(die_length 12.714)
			(solder_mask_margin 0.075)
		)
		(pad "T15" smd circle
			(at 1.5 2.5 90)
			(size 0.5 0.5)
			(layers "F.Cu" "F.Mask" "F.Paste")
			(net 553 "+0V85")
			(pinfunction "VCCINT")
			(pintype "passive")
			(solder_mask_margin 0.075)
		)
		(pad "T16" smd circle
			(at 2.5 2.5 90)
			(size 0.5 0.5)
			(layers "F.Cu" "F.Mask" "F.Paste")
			(net 1 "GND")
			(pinfunction "GND")
			(pintype "passive")
			(solder_mask_margin 0.075)
		)
		(pad "T17" smd circle
			(at 3.5 2.5 90)
			(size 0.5 0.5)
			(layers "F.Cu" "F.Mask" "F.Paste")
			(net 553 "+0V85")
			(pinfunction "VCCINT")
			(pintype "passive")
			(solder_mask_margin 0.075)
		)
		(pad "T18" smd circle
			(at 4.5 2.5 90)
			(size 0.5 0.5)
			(layers "F.Cu" "F.Mask" "F.Paste")
			(net 797 "+1V8")
			(pinfunction "VCCAUX_IO")
			(pintype "passive")
			(solder_mask_margin 0.075)
		)
		(pad "T19" smd circle
			(at 5.5 2.5 90)
			(size 0.5 0.5)
			(layers "F.Cu" "F.Mask" "F.Paste")
			(net 190 "/DDR5 RDIMM/CTRL.~{RESET}")
			(pinfunction "IO_T3U_N12_PERSTN0_65")
			(pintype "bidirectional")
			(die_length 14.756)
			(solder_mask_margin 0.075)
		)
		(pad "T20" smd circle
			(at 6.5 2.5 90)
			(size 0.5 0.5)
			(layers "F.Cu" "F.Mask" "F.Paste")
			(net 171 "/DDR5 RDIMM/A.CB2")
			(pinfunction "IO_L3P_T0L_N4_AD15P_A26_65")
			(pintype "bidirectional")
			(die_length 11.445)
			(solder_mask_margin 0.075)
		)
		(pad "T21" smd circle
			(at 7.5 2.5 90)
			(size 0.5 0.5)
			(layers "F.Cu" "F.Mask" "F.Paste")
			(net 1 "GND")
			(pinfunction "GND")
			(pintype "passive")
			(solder_mask_margin 0.075)
		)
		(pad "T22" smd circle
			(at 8.5 2.5 90)
			(size 0.5 0.5)
			(layers "F.Cu" "F.Mask" "F.Paste")
			(net 186 "/DDR5 RDIMM/A.CB6")
			(pinfunction "IO_L5P_T0U_N8_AD14P_A22_65")
			(pintype "bidirectional")
			(die_length 9.497)
			(solder_mask_margin 0.075)
		)
		(pad "T23" smd circle
			(at 9.5 2.5 90)
			(size 0.5 0.5)
			(layers "F.Cu" "F.Mask" "F.Paste")
			(net 70 "/DDR5 RDIMM/A.CB4")
			(pinfunction "IO_L5N_T0U_N9_AD14N_A23_65")
			(pintype "bidirectional")
			(die_length 9.52)
			(solder_mask_margin 0.075)
		)
		(pad "T24" smd circle
			(at 10.5 2.5 90)
			(size 0.5 0.5)
			(layers "F.Cu" "F.Mask" "F.Paste")
			(net 83 "/DDR5 RDIMM/B.CS0_c")
			(pinfunction "IO_L13P_T2L_N0_GC_QBC_A06_D22_65")
			(pintype "bidirectional")
			(die_length 10.564)
			(solder_mask_margin 0.075)
		)
		(pad "T25" smd circle
			(at 11.5 2.5 90)
			(size 0.5 0.5)
			(layers "F.Cu" "F.Mask" "F.Paste")
			(net 198 "/DDR5 RDIMM/B.CA2")
			(pinfunction "IO_L14P_T2L_N2_GC_A04_D20_65")
			(pintype "bidirectional")
			(die_length 11.424)
			(solder_mask_margin 0.075)
		)
		(pad "T26" smd circle
			(at 12.5 2.5 90)
			(size 0.5 0.5)
			(layers "F.Cu" "F.Mask" "F.Paste")
			(net 1 "GND")
			(pinfunction "GND")
			(pintype "passive")
			(solder_mask_margin 0.075)
		)
		(pad "U1" smd circle
			(at -12.5 3.5 90)
			(size 0.5 0.5)
			(layers "F.Cu" "F.Mask" "F.Paste")
			(net 1 "GND")
			(pinfunction "GND")
			(pintype "passive")
			(solder_mask_margin 0.075)
		)
		(pad "U2" smd circle
			(at -11.5 3.5 90)
			(size 0.5 0.5)
			(layers "F.Cu" "F.Mask" "F.Paste")
			(net 1 "GND")
			(pinfunction "GND")
			(pintype "passive")
			(solder_mask_margin 0.075)
		)
		(pad "U3" smd circle
			(at -10.5 3.5 90)
			(size 0.5 0.5)
			(layers "F.Cu" "F.Mask" "F.Paste")
			(net 1 "GND")
			(pinfunction "GND")
			(pintype "passive")
			(solder_mask_margin 0.075)
		)
		(pad "U4" smd circle
			(at -9.5 3.5 90)
			(size 0.5 0.5)
			(layers "F.Cu" "F.Mask" "F.Paste")
			(net 29 "/FPGA MGT Interface/GTY_225_TX2_N")
			(pinfunction "MGTYTXN2_225")
			(pintype "output")
			(die_length 8.698)
			(solder_mask_margin 0.075)
		)
		(pad "U5" smd circle
			(at -8.5 3.5 90)
			(size 0.5 0.5)
			(layers "F.Cu" "F.Mask" "F.Paste")
			(net 20 "/FPGA MGT Interface/GTY_225_TX2_P")
			(pinfunction "MGTYTXP2_225")
			(pintype "output")
			(die_length 8.717)
			(solder_mask_margin 0.075)
		)
		(pad "U6" smd circle
			(at -7.5 3.5 90)
			(size 0.5 0.5)
			(layers "F.Cu" "F.Mask" "F.Paste")
			(net 1 "GND")
			(pinfunction "GND")
			(pintype "passive")
			(solder_mask_margin 0.075)
		)
		(pad "U7" smd circle
			(at -6.5 3.5 90)
			(size 0.5 0.5)
			(layers "F.Cu" "F.Mask" "F.Paste")
			(net 573 "+1V8_MGTVCCAUX")
			(pinfunction "MGTVCCAUX_R")
			(pintype "passive")
			(solder_mask_margin 0.075)
		)
		(pad "U8" smd circle
			(at -5.5 3.5 90)
			(size 0.5 0.5)
			(layers "F.Cu" "F.Mask" "F.Paste")
			(net 1 "GND")
			(pinfunction "GND")
			(pintype "passive")
			(solder_mask_margin 0.075)
		)
		(pad "U9" smd circle
			(at -4.5 3.5 90)
			(size 0.5 0.5)
			(layers "F.Cu" "F.Mask" "F.Paste")
			(net 553 "+0V85")
			(pinfunction "VCCBRAM")
			(pintype "passive")
			(solder_mask_margin 0.075)
		)
		(pad "U10" smd circle
			(at -3.5 3.5 90)
			(size 0.5 0.5)
			(layers "F.Cu" "F.Mask" "F.Paste")
			(net 553 "+0V85")
			(pinfunction "VCCINT")
			(pintype "passive")
			(solder_mask_margin 0.075)
		)
		(pad "U11" smd circle
			(at -2.5 3.5 90)
			(size 0.5 0.5)
			(layers "F.Cu" "F.Mask" "F.Paste")
			(net 1 "GND")
			(pinfunction "GND")
			(pintype "passive")
			(solder_mask_margin 0.075)
		)
		(pad "U12" smd circle
			(at -1.5 3.5 90)
			(size 0.5 0.5)
			(layers "F.Cu" "F.Mask" "F.Paste")
			(net 553 "+0V85")
			(pinfunction "VCCINT")
			(pintype "passive")
			(solder_mask_margin 0.075)
		)
		(pad "U13" smd circle
			(at -0.5 3.5 90)
			(size 0.5 0.5)
			(layers "F.Cu" "F.Mask" "F.Paste")
			(net 1 "GND")
			(pinfunction "GND")
			(pintype "passive")
			(solder_mask_margin 0.075)
		)
		(pad "U14" smd circle
			(at 0.5 3.5 90)
			(size 0.5 0.5)
			(layers "F.Cu" "F.Mask" "F.Paste")
			(net 553 "+0V85")
			(pinfunction "VCCINT")
			(pintype "passive")
			(solder_mask_margin 0.075)
		)
		(pad "U15" smd circle
			(at 1.5 3.5 90)
			(size 0.5 0.5)
			(layers "F.Cu" "F.Mask" "F.Paste")
			(net 1 "GND")
			(pinfunction "GND")
			(pintype "passive")
			(solder_mask_margin 0.075)
		)
		(pad "U16" smd circle
			(at 2.5 3.5 90)
			(size 0.5 0.5)
			(layers "F.Cu" "F.Mask" "F.Paste")
			(net 553 "+0V85")
			(pinfunction "VCCINT")
			(pintype "passive")
			(solder_mask_margin 0.075)
		)
		(pad "U17" smd circle
			(at 3.5 3.5 90)
			(size 0.5 0.5)
			(layers "F.Cu" "F.Mask" "F.Paste")
			(net 1 "GND")
			(pinfunction "GND")
			(pintype "passive")
			(solder_mask_margin 0.075)
		)
		(pad "U18" smd circle
			(at 4.5 3.5 90)
			(size 0.5 0.5)
			(layers "F.Cu" "F.Mask" "F.Paste")
			(net 1 "GND")
			(pinfunction "GND")
			(pintype "passive")
			(solder_mask_margin 0.075)
		)
		(pad "U19" smd circle
			(at 5.5 3.5 90)
			(size 0.5 0.5)
			(layers "F.Cu" "F.Mask" "F.Paste")
			(net 120 "/DDR5 RDIMM/A.DQS4_P")
			(pinfunction "IO_L1P_T0L_N0_DBC_RS0_65")
			(pintype "bidirectional")
			(die_length 11.98)
			(solder_mask_margin 0.075)
		)
		(pad "U20" smd circle
			(at 6.5 3.5 90)
			(size 0.5 0.5)
			(layers "F.Cu" "F.Mask" "F.Paste")
			(net 173 "/DDR5 RDIMM/A.CB3")
			(pinfunction "IO_L3N_T0L_N5_AD15N_A27_65")
			(pintype "bidirectional")
			(die_length 11.601)
			(solder_mask_margin 0.075)
		)
		(pad "U21" smd circle
			(at 7.5 3.5 90)
			(size 0.5 0.5)
			(layers "F.Cu" "F.Mask" "F.Paste")
			(net 68 "/DDR5 RDIMM/A.CB1")
			(pinfunction "IO_L2P_T0L_N2_FOE_B_65")
			(pintype "bidirectional")
			(die_length 9.565)
			(solder_mask_margin 0.075)
		)
		(pad "U22" smd circle
			(at 8.5 3.5 90)
			(size 0.5 0.5)
			(layers "F.Cu" "F.Mask" "F.Paste")
			(net 67 "/DDR5 RDIMM/A.CB0")
			(pinfunction "IO_L2N_T0L_N3_FWE_FCS2_B_65")
			(pintype "bidirectional")
			(die_length 9.453)
			(solder_mask_margin 0.075)
		)
		(pad "U23" smd circle
			(at 9.5 3.5 90)
			(size 0.5 0.5)
			(layers "F.Cu" "F.Mask" "F.Paste")
			(net 687 "VDDQ")
			(pinfunction "VCCO_65")
			(pintype "passive")
			(solder_mask_margin 0.075)
		)
		(pad "U24" smd circle
			(at 10.5 3.5 90)
			(size 0.5 0.5)
			(layers "F.Cu" "F.Mask" "F.Paste")
			(net 203 "/DDR5 RDIMM/B.CS1_c")
			(pinfunction "IO_L13N_T2L_N1_GC_QBC_A07_D23_65")
			(pintype "bidirectional")
			(die_length 10.66)
			(solder_mask_margin 0.075)
		)
		(pad "U25" smd circle
			(at 11.5 3.5 90)
			(size 0.5 0.5)
			(layers "F.Cu" "F.Mask" "F.Paste")
			(net 79 "/DDR5 RDIMM/B.CA0")
			(pinfunction "IO_L14N_T2L_N3_GC_A05_D21_65")
			(pintype "bidirectional")
			(die_length 11.487)
			(solder_mask_margin 0.075)
		)
		(pad "U26" smd circle
			(at 12.5 3.5 90)
			(size 0.5 0.5)
			(layers "F.Cu" "F.Mask" "F.Paste")
			(net 84 "/DDR5 RDIMM/CTRL.DLBDQ")
			(pinfunction "IO_L16P_T2U_N6_QBC_AD3P_A00_D16_65")
			(pintype "bidirectional")
			(die_length 11.914)
			(solder_mask_margin 0.075)
		)
		(pad "V1" smd circle
			(at -12.5 4.5 90)
			(size 0.5 0.5)
			(layers "F.Cu" "F.Mask" "F.Paste")
			(net 337 "/FPGA MGT Interface/PCIE.RXD2_N")
			(pinfunction "MGTYRXN1_225")
			(pintype "input")
			(die_length 10.53)
			(solder_mask_margin 0.075)
		)
		(pad "V2" smd circle
			(at -11.5 4.5 90)
			(size 0.5 0.5)
			(layers "F.Cu" "F.Mask" "F.Paste")
			(net 336 "/FPGA MGT Interface/PCIE.RXD2_P")
			(pinfunction "MGTYRXP1_225")
			(pintype "input")
			(die_length 10.52)
			(solder_mask_margin 0.075)
		)
		(pad "V3" smd circle
			(at -10.5 4.5 90)
			(size 0.5 0.5)
			(layers "F.Cu" "F.Mask" "F.Paste")
			(net 1 "GND")
			(pinfunction "GND")
			(pintype "passive")
			(solder_mask_margin 0.075)
		)
		(pad "V4" smd circle
			(at -9.5 4.5 90)
			(size 0.5 0.5)
			(layers "F.Cu" "F.Mask" "F.Paste")
			(net 1 "GND")
			(pinfunction "GND")
			(pintype "passive")
			(solder_mask_margin 0.075)
		)
		(pad "V5" smd circle
			(at -8.5 4.5 90)
			(size 0.5 0.5)
			(layers "F.Cu" "F.Mask" "F.Paste")
			(net 172 "+1V2_MGTAVTT")
			(pinfunction "MGTAVTT_R")
			(pintype "passive")
			(solder_mask_margin 0.075)
		)
		(pad "V6" smd circle
			(at -7.5 4.5 90)
			(size 0.5 0.5)
			(layers "F.Cu" "F.Mask" "F.Paste")
			(net 564 "unconnected-(U34J-MGTREFCLK0N_225-PadV6)")
			(pinfunction "MGTREFCLK0N_225")
			(pintype "input+no_connect")
			(die_length 7.84)
			(solder_mask_margin 0.075)
		)
		(pad "V7" smd circle
			(at -6.5 4.5 90)
			(size 0.5 0.5)
			(layers "F.Cu" "F.Mask" "F.Paste")
			(net 565 "unconnected-(U34J-MGTREFCLK0P_225-PadV7)")
			(pinfunction "MGTREFCLK0P_225")
			(pintype "input+no_connect")
			(die_length 7.861)
			(solder_mask_margin 0.075)
		)
	)
)
